FILE_TYPE = CONNECTIVITY;
{Allegro Design Entry HDL 16.6-p007 (v16-6-112F) 10/10/2012}
"PAGE_NUMBER" = 80;
0"NC";
1"M_H_DQS_DP<17:0>";
2"M_H_DQS_DN<17:0>";
3"M_H_DQ<63:0>";
4"M_H_MA<17:0>";
5"M_H_BA<1:0>";
6"M_H_BG<1:0>";
7"M_H_CLK_DN<3:0>";
8"M_H_CS_N<7:0>";
9"M_H_CKE<3:0>";
10"M_H_CLK_DP<3:0>";
11"M_H_ODT<3:0>";
12"M_H_ECC<7:0>";
13"GND\g";
14"GND\g";
15"GND\g";
16"P12V_NVDIMM_GHJ\g";
17"GND\g";
18"PVDDQ_GHJ\g";
19"PVTT_GHJ\g";
20"PVPP_GHJ\g";
21"PVPP_GHJ\g";
22"FM_DIMM_EVENT_COD_N";
23"M_H_VREF";
24"TP_CH_H_DIMM0_RFU_2";
25"TP_CH_H_DIMM0_RFU_0";
26"TP_CH_H_DIMM0_RFU_1";
27"M_H_ACT_N";
28"FM_ADR_COMPLETE_GHJ_N";
29"SMB_DDR_GHJ_VPP_SCL";
30"SMB_DDR_GHJ_VPP_SDA";
31"M_H_ALERT_N";
32"M_H_ECC<1>";
33"M_H_ECC<0>";
34"M_H_DQ<16>";
35"M_H_DQ<13>";
36"M_H_DQ<11>";
37"M_H_DQ<10>";
38"M_H_DQ<8>";
39"M_H_DQ<6>";
40"M_H_DQ<1>";
41"M_H_DQ<0>";
42"M_H_DQ<15>";
43"M_H_DQ<4>";
44"M_H_DQ<2>";
45"M_H_DQ<3>";
46"M_H_DQ<7>";
47"M_H_DQ<9>";
48"M_H_DQ<14>";
49"M_H_DQ<5>";
50"M_H_DQ<12>";
51"M_H_PAR";
52"M_GHJ_RST_N";
53"M_H_ECC<6>";
54"M_H_ECC<5>";
55"M_H_ECC<4>";
56"M_H_ECC<3>";
57"M_H_ECC<2>";
58"M_H_ECC<7>";
59"M_H_ODT<2>";
60"M_H_ODT<3>";
61"M_H_CKE<2>";
62"M_H_C<2>";
63"M_H_CLK_DP<2>";
64"M_H_CS_N<7>";
65"M_H_CS_N<6>";
66"M_H_CS_N<5>";
67"M_H_CKE<3>";
68"M_H_CS_N<4>";
69"M_H_CLK_DN<2>";
70"M_H_BA<1>";
71"M_H_MA<0>";
72"M_H_MA<1>";
73"M_H_BG<0>";
74"M_H_BG<1>";
75"M_H_BA<0>";
76"M_H_CLK_DP<3>";
77"M_H_CLK_DN<3>";
78"M_H_MA<3>";
79"M_H_MA<4>";
80"M_H_MA<5>";
81"M_H_MA<6>";
82"M_H_MA<7>";
83"M_H_MA<8>";
84"M_H_MA<9>";
85"M_H_MA<2>";
86"M_H_MA<10>";
87"M_H_MA<11>";
88"M_H_DQ<29>";
89"M_H_DQ<28>";
90"M_H_DQ<37>";
91"M_H_DQ<34>";
92"M_H_DQ<33>";
93"M_H_DQ<32>";
94"M_H_DQ<31>";
95"M_H_DQ<30>";
96"M_H_DQ<24>";
97"M_H_DQ<22>";
98"M_H_DQ<21>";
99"M_H_DQ<20>";
100"M_H_DQ<18>";
101"M_H_DQ<35>";
102"M_H_DQ<36>";
103"M_H_DQ<27>";
104"M_H_DQ<17>";
105"M_H_DQ<23>";
106"M_H_DQ<25>";
107"M_H_DQ<26>";
108"M_H_DQ<19>";
109"M_H_DQ<56>";
110"M_H_DQ<55>";
111"M_H_DQ<46>";
112"M_H_DQ<45>";
113"M_H_DQ<44>";
114"M_H_DQ<43>";
115"M_H_DQ<42>";
116"M_H_DQ<41>";
117"M_H_DQ<40>";
118"M_H_DQ<39>";
119"M_H_DQ<38>";
120"M_H_DQ<57>";
121"M_H_DQ<54>";
122"M_H_DQ<53>";
123"M_H_DQ<52>";
124"M_H_DQ<51>";
125"M_H_DQ<49>";
126"M_H_DQ<48>";
127"M_H_DQ<47>";
128"M_H_DQ<50>";
129"M_H_MA<12>";
130"M_H_MA<13>";
131"M_H_MA<17>";
132"M_H_MA<14>";
133"M_H_MA<15>";
134"M_H_MA<16>";
135"M_H_DQ<61>";
136"M_H_DQ<60>";
137"M_H_DQ<59>";
138"M_H_DQ<58>";
139"M_H_DQ<62>";
140"M_H_DQ<63>";
141"M_H_DQS_DN<0>";
142"M_H_DQS_DP<0>";
143"M_H_DQS_DN<10>";
144"M_H_DQS_DP<10>";
145"M_H_DQS_DN<11>";
146"M_H_DQS_DP<11>";
147"M_H_DQS_DN<12>";
148"M_H_DQS_DN<1>";
149"M_H_DQS_DP<1>";
150"M_H_DQS_DN<2>";
151"M_H_DQS_DP<2>";
152"M_H_DQS_DN<3>";
153"M_H_DQS_DP<3>";
154"M_H_DQS_DN<4>";
155"M_H_DQS_DP<4>";
156"M_H_DQS_DN<5>";
157"M_H_DQS_DP<5>";
158"M_H_DQS_DN<6>";
159"M_H_DQS_DP<6>";
160"M_H_DQS_DN<7>";
161"M_H_DQS_DP<7>";
162"M_H_DQS_DN<8>";
163"M_H_DQS_DP<8>";
164"M_H_DQS_DN<9>";
165"M_H_DQS_DP<9>";
166"M_H_DQS_DP<12>";
167"M_H_DQS_DN<13>";
168"M_H_DQS_DP<13>";
169"M_H_DQS_DN<14>";
170"M_H_DQS_DP<14>";
171"M_H_DQS_DN<15>";
172"M_H_DQS_DP<15>";
173"M_H_DQS_DN<16>";
174"M_H_DQS_DP<16>";
175"M_H_DQS_DN<17>";
176"M_H_DQS_DP<17>";
%"GND"
"1","(-7825,1350)","2","mstr_symbols","I1";
;
HDL_POWER"GND"
ROOM"DDR4_GH_G"
BODY_TYPE"PLUMBING"
BOM_COST"MEM"
SIZE"1B"
CDS_LIB"mstr_symbols"
VOLTAGE"0";
"A\NAC"13;
%"TAP"
"6","(-4475,3450)","2","mstr_standard","I100";
;
HDL_TAP"TRUE"
BODY_TYPE"PLUMBING"
CDS_LIB"mstr_standard";
"B \NAC \NWC"3;
"S \NAC"
BN"45"112;
%"SCONN288_H44441003"
"2","(-2675,3750)","0","mstr_sconn","I101";
;
CDS_SEC"2"
ROOM"DDR4_GH_H"
CDS_LOCATION"J9U1"
SEC"2"
SEC_TYPE"PIP"
CDS_LIB"mstr_sconn"
BOM_COST"MEM"
PACK_TYPE"PIP"
MATERIAL"SCONN"
PART_NUMBER"H44441-003"
LOCATION"J9U1";
"DQS0N"
$PN"152"141;
"DQS0P"
$PN"153"142;
"DQS10N"
$PN"19"143;
"DQS10P"
$PN"18"144;
"DQS11N"
$PN"30"145;
"DQS11P"
$PN"29"146;
"DQS12N"
$PN"41"147;
"DQS12P"
$PN"40"166;
"DQS13N"
$PN"100"167;
"DQS13P"
$PN"99"168;
"DQS14N"
$PN"111"169;
"DQS14P"
$PN"110"170;
"DQS15N"
$PN"122"171;
"DQS15P"
$PN"121"172;
"DQS16N"
$PN"133"173;
"DQS16P"
$PN"132"174;
"DQS17N"
$PN"52"175;
"DQS17P"
$PN"51"176;
"DQS1N"
$PN"163"148;
"DQS1P"
$PN"164"149;
"DQS2N"
$PN"174"150;
"DQS2P"
$PN"175"151;
"DQS3N"
$PN"185"152;
"DQS3P"
$PN"186"153;
"DQS4N"
$PN"244"154;
"DQS4P"
$PN"245"155;
"DQS5N"
$PN"255"156;
"DQS5P"
$PN"256"157;
"DQS6N"
$PN"266"158;
"DQS6P"
$PN"267"159;
"DQS7N"
$PN"277"160;
"DQS7P"
$PN"278"161;
"DQS8N"
$PN"196"162;
"DQS8P"
$PN"197"163;
"DQS9N"
$PN"8"164;
"DQS9P"
$PN"7"165;
%"TAP"
"6","(-5975,3550)","0","mstr_standard","I102";
;
HDL_TAP"TRUE"
BODY_TYPE"PLUMBING"
CDS_LIB"mstr_standard";
"B \NAC \NWC"4;
"S \NAC"
BN"1"72;
%"TAP"
"6","(-5975,3600)","0","mstr_standard","I103";
;
HDL_TAP"TRUE"
BODY_TYPE"PLUMBING"
CDS_LIB"mstr_standard";
"B \NAC \NWC"4;
"S \NAC"
BN"2"85;
%"TAP"
"6","(-5975,3650)","0","mstr_standard","I104";
;
HDL_TAP"TRUE"
BODY_TYPE"PLUMBING"
CDS_LIB"mstr_standard";
"B \NAC \NWC"4;
"S \NAC"
BN"3"78;
%"TAP"
"6","(-5975,3750)","0","mstr_standard","I105";
;
HDL_TAP"TRUE"
BODY_TYPE"PLUMBING"
CDS_LIB"mstr_standard";
"B \NAC \NWC"4;
"S \NAC"
BN"5"80;
%"TAP"
"6","(-5975,3700)","0","mstr_standard","I106";
;
HDL_TAP"TRUE"
BODY_TYPE"PLUMBING"
CDS_LIB"mstr_standard";
"B \NAC \NWC"4;
"S \NAC"
BN"4"79;
%"TAP"
"6","(-5975,3800)","0","mstr_standard","I107";
;
HDL_TAP"TRUE"
BODY_TYPE"PLUMBING"
CDS_LIB"mstr_standard";
"B \NAC \NWC"4;
"S \NAC"
BN"6"81;
%"TAP"
"6","(-5975,3900)","0","mstr_standard","I108";
;
HDL_TAP"TRUE"
BODY_TYPE"PLUMBING"
CDS_LIB"mstr_standard";
"B \NAC \NWC"4;
"S \NAC"
BN"8"83;
%"TAP"
"6","(-5975,3850)","0","mstr_standard","I109";
;
HDL_TAP"TRUE"
BODY_TYPE"PLUMBING"
CDS_LIB"mstr_standard";
"B \NAC \NWC"4;
"S \NAC"
BN"7"82;
%"TAP"
"6","(-5975,4000)","0","mstr_standard","I110";
;
HDL_TAP"TRUE"
BODY_TYPE"PLUMBING"
CDS_LIB"mstr_standard";
"B \NAC \NWC"4;
"S \NAC"
BN"10"86;
%"TAP"
"6","(-5975,3950)","0","mstr_standard","I111";
;
HDL_TAP"TRUE"
BODY_TYPE"PLUMBING"
CDS_LIB"mstr_standard";
"B \NAC \NWC"4;
"S \NAC"
BN"9"84;
%"TAP"
"6","(-5975,4050)","0","mstr_standard","I112";
;
HDL_TAP"TRUE"
BODY_TYPE"PLUMBING"
CDS_LIB"mstr_standard";
"B \NAC \NWC"4;
"S \NAC"
BN"11"87;
%"TAP"
"6","(-5975,4100)","0","mstr_standard","I113";
;
HDL_TAP"TRUE"
BODY_TYPE"PLUMBING"
CDS_LIB"mstr_standard";
"B \NAC \NWC"4;
"S \NAC"
BN"12"129;
%"TAP"
"6","(-5975,4150)","0","mstr_standard","I114";
;
HDL_TAP"TRUE"
BODY_TYPE"PLUMBING"
CDS_LIB"mstr_standard";
"B \NAC \NWC"4;
"S \NAC"
BN"13"130;
%"TAP"
"6","(-5975,4250)","0","mstr_standard","I115";
;
HDL_TAP"TRUE"
BODY_TYPE"PLUMBING"
CDS_LIB"mstr_standard";
"B \NAC \NWC"4;
"S \NAC"
BN"15"133;
%"TAP"
"6","(-5975,4200)","0","mstr_standard","I116";
;
HDL_TAP"TRUE"
BODY_TYPE"PLUMBING"
CDS_LIB"mstr_standard";
"B \NAC \NWC"4;
"S \NAC"
BN"14"132;
%"TAP"
"6","(-5975,4300)","0","mstr_standard","I117";
;
HDL_TAP"TRUE"
BODY_TYPE"PLUMBING"
CDS_LIB"mstr_standard";
"B \NAC \NWC"4;
"S \NAC"
BN"16"134;
%"TAP"
"6","(-5975,4350)","0","mstr_standard","I118";
;
HDL_TAP"TRUE"
BODY_TYPE"PLUMBING"
CDS_LIB"mstr_standard";
"B \NAC \NWC"4;
"S \NAC"
BN"17"131;
%"TAP"
"6","(-4475,3550)","2","mstr_standard","I119";
;
HDL_TAP"TRUE"
BODY_TYPE"PLUMBING"
CDS_LIB"mstr_standard";
"B \NAC \NWC"3;
"S \NAC"
BN"47"127;
%"TAP"
"6","(-4475,3600)","2","mstr_standard","I120";
;
HDL_TAP"TRUE"
BODY_TYPE"PLUMBING"
CDS_LIB"mstr_standard";
"B \NAC \NWC"3;
"S \NAC"
BN"48"126;
%"TAP"
"6","(-4475,3650)","2","mstr_standard","I121";
;
HDL_TAP"TRUE"
BODY_TYPE"PLUMBING"
CDS_LIB"mstr_standard";
"B \NAC \NWC"3;
"S \NAC"
BN"49"125;
%"TAP"
"6","(-4475,3800)","2","mstr_standard","I122";
;
HDL_TAP"TRUE"
BODY_TYPE"PLUMBING"
CDS_LIB"mstr_standard";
"B \NAC \NWC"3;
"S \NAC"
BN"52"123;
%"TAP"
"6","(-4475,3700)","2","mstr_standard","I123";
;
HDL_TAP"TRUE"
BODY_TYPE"PLUMBING"
CDS_LIB"mstr_standard";
"B \NAC \NWC"3;
"S \NAC"
BN"50"128;
%"TAP"
"6","(-4475,3750)","2","mstr_standard","I124";
;
HDL_TAP"TRUE"
BODY_TYPE"PLUMBING"
CDS_LIB"mstr_standard";
"B \NAC \NWC"3;
"S \NAC"
BN"51"124;
%"TAP"
"6","(-4475,3850)","2","mstr_standard","I125";
;
HDL_TAP"TRUE"
BODY_TYPE"PLUMBING"
CDS_LIB"mstr_standard";
"B \NAC \NWC"3;
"S \NAC"
BN"53"122;
%"TAP"
"6","(-4475,3900)","2","mstr_standard","I126";
;
HDL_TAP"TRUE"
BODY_TYPE"PLUMBING"
CDS_LIB"mstr_standard";
"B \NAC \NWC"3;
"S \NAC"
BN"54"121;
%"TAP"
"6","(-4475,4050)","2","mstr_standard","I127";
;
HDL_TAP"TRUE"
BODY_TYPE"PLUMBING"
CDS_LIB"mstr_standard";
"B \NAC \NWC"3;
"S \NAC"
BN"57"120;
%"TAP"
"6","(-4475,3950)","2","mstr_standard","I128";
;
HDL_TAP"TRUE"
BODY_TYPE"PLUMBING"
CDS_LIB"mstr_standard";
"B \NAC \NWC"3;
"S \NAC"
BN"55"110;
%"TAP"
"6","(-4475,4000)","2","mstr_standard","I129";
;
HDL_TAP"TRUE"
BODY_TYPE"PLUMBING"
CDS_LIB"mstr_standard";
"B \NAC \NWC"3;
"S \NAC"
BN"56"109;
%"TAP"
"6","(-4475,4150)","2","mstr_standard","I130";
;
HDL_TAP"TRUE"
BODY_TYPE"PLUMBING"
CDS_LIB"mstr_standard";
"B \NAC \NWC"3;
"S \NAC"
BN"59"137;
%"TAP"
"6","(-4475,4100)","2","mstr_standard","I131";
;
HDL_TAP"TRUE"
BODY_TYPE"PLUMBING"
CDS_LIB"mstr_standard";
"B \NAC \NWC"3;
"S \NAC"
BN"58"138;
%"TAP"
"6","(-4475,4300)","2","mstr_standard","I132";
;
HDL_TAP"TRUE"
BODY_TYPE"PLUMBING"
CDS_LIB"mstr_standard";
"B \NAC \NWC"3;
"S \NAC"
BN"62"139;
%"TAP"
"6","(-4475,4200)","2","mstr_standard","I133";
;
HDL_TAP"TRUE"
BODY_TYPE"PLUMBING"
CDS_LIB"mstr_standard";
"B \NAC \NWC"3;
"S \NAC"
BN"60"136;
%"TAP"
"6","(-4475,4250)","2","mstr_standard","I134";
;
HDL_TAP"TRUE"
BODY_TYPE"PLUMBING"
CDS_LIB"mstr_standard";
"B \NAC \NWC"3;
"S \NAC"
BN"61"135;
%"TAP"
"6","(-4475,4350)","2","mstr_standard","I135";
;
HDL_TAP"TRUE"
BODY_TYPE"PLUMBING"
CDS_LIB"mstr_standard";
"B \NAC \NWC"3;
"S \NAC"
BN"63"140;
%"GND"
"1","(-1575,550)","2","mstr_symbols","I137";
;
HDL_POWER"GND"
ROOM"DDR4_GH_G"
BODY_TYPE"PLUMBING"
BOM_COST"MEM"
SIZE"1B"
CDS_LIB"mstr_symbols"
VOLTAGE"0";
"A\NAC"14;
%"SCONN288_H44441003"
"3","(-875,1850)","0","mstr_sconn","I138";
;
CDS_SEC"3"
ROOM"DDR4_GH_H"
CDS_LOCATION"J9U1"
SEC"3"
SEC_TYPE"PIP"
CDS_LIB"mstr_sconn"
BOM_COST"MEM"
PACK_TYPE"PIP"
MATERIAL"SCONN"
PART_NUMBER"H44441-003"
LOCATION"J9U1";
"VSS<46>"
$PN"147"15;
"VSS<45>"
$PN"149"15;
"VSS<87>"
$PN"15"14;
"VSS<86>"
$PN"17"14;
"VSS<85>"
$PN"20"14;
"VSS<84>"
$PN"22"14;
"VSS<83>"
$PN"24"14;
"VSS<82>"
$PN"26"14;
"VSS<81>"
$PN"28"14;
"VSS<80>"
$PN"31"14;
"VSS<79>"
$PN"33"14;
"VSS<78>"
$PN"35"14;
"VSS<77>"
$PN"37"14;
"VSS<76>"
$PN"39"14;
"VSS<75>"
$PN"42"14;
"VSS<74>"
$PN"44"14;
"VSS<73>"
$PN"46"14;
"VSS<72>"
$PN"48"14;
"VSS<71>"
$PN"50"14;
"VSS<70>"
$PN"53"14;
"VSS<69>"
$PN"55"14;
"VSS<68>"
$PN"57"14;
"VSS<67>"
$PN"94"14;
"VSS<66>"
$PN"96"14;
"VSS<65>"
$PN"98"14;
"VSS<64>"
$PN"101"14;
"VSS<63>"
$PN"103"14;
"VSS<62>"
$PN"105"14;
"VSS<61>"
$PN"107"14;
"VSS<60>"
$PN"109"14;
"VSS<59>"
$PN"112"14;
"VSS<58>"
$PN"114"14;
"VSS<57>"
$PN"116"14;
"VSS<56>"
$PN"118"14;
"VSS<55>"
$PN"120"14;
"VSS<54>"
$PN"123"14;
"VSS<53>"
$PN"125"14;
"VSS<52>"
$PN"127"14;
"VSS<51>"
$PN"129"14;
"VSS<50>"
$PN"131"14;
"VSS<49>"
$PN"134"14;
"VSS<48>"
$PN"136"14;
"VSS<47>"
$PN"138"14;
"VSS<44>"
$PN"151"15;
"VSS<43>"
$PN"154"15;
"VSS<42>"
$PN"156"15;
"VSS<41>"
$PN"158"15;
"VSS<40>"
$PN"160"15;
"VSS<39>"
$PN"162"15;
"VSS<38>"
$PN"165"15;
"VSS<37>"
$PN"167"15;
"VSS<36>"
$PN"169"15;
"VSS<35>"
$PN"171"15;
"VSS<34>"
$PN"173"15;
"VSS<33>"
$PN"176"15;
"VSS<32>"
$PN"178"15;
"VSS<31>"
$PN"180"15;
"VSS<30>"
$PN"182"15;
"VSS<29>"
$PN"184"15;
"VSS<28>"
$PN"187"15;
"VSS<27>"
$PN"189"15;
"VSS<26>"
$PN"191"15;
"VSS<25>"
$PN"193"15;
"VSS<24>"
$PN"195"15;
"VSS<23>"
$PN"198"15;
"VSS<22>"
$PN"200"15;
"VSS<21>"
$PN"202"15;
"VSS<20>"
$PN"239"15;
"VSS<19>"
$PN"241"15;
"VSS<18>"
$PN"243"15;
"VSS<17>"
$PN"246"15;
"VSS<16>"
$PN"248"15;
"VSS<15>"
$PN"250"15;
"VSS<14>"
$PN"252"15;
"VSS<13>"
$PN"254"15;
"VSS<12>"
$PN"257"15;
"VSS<11>"
$PN"259"15;
"VSS<10>"
$PN"261"15;
"VSS<9>"
$PN"263"15;
"VSS<8>"
$PN"265"15;
"VSS<7>"
$PN"268"15;
"VSS<6>"
$PN"270"15;
"VSS<5>"
$PN"272"15;
"VSS<4>"
$PN"274"15;
"VSS<3>"
$PN"276"15;
"VSS<2>"
$PN"279"15;
"VSS<1>"
$PN"281"15;
"VSS<0>"
$PN"283"15;
"VSS<88>"
$PN"13"14;
"VSS<89>"
$PN"11"14;
"VSS<90>"
$PN"9"14;
"VSS<91>"
$PN"6"14;
"VSS<92>"
$PN"4"14;
"VSS<93>"
$PN"2"14;
%"TAP"
"6","(-1975,3000)","2","mstr_standard","I142";
;
HDL_TAP"TRUE"
BODY_TYPE"PLUMBING"
CDS_LIB"mstr_standard";
"B \NAC \NWC"1;
"S \NAC"
BN"1"149;
%"TAP"
"6","(-1975,2900)","2","mstr_standard","I143";
;
HDL_TAP"TRUE"
BODY_TYPE"PLUMBING"
CDS_LIB"mstr_standard";
"B \NAC \NWC"1;
"S \NAC"
BN"0"142;
%"TAP"
"6","(-1775,2850)","2","mstr_standard","I144";
;
HDL_TAP"TRUE"
BODY_TYPE"PLUMBING"
CDS_LIB"mstr_standard";
"B \NAC \NWC"2;
"S \NAC"
BN"0"141;
%"TAP"
"6","(-1775,2950)","2","mstr_standard","I145";
;
HDL_TAP"TRUE"
BODY_TYPE"PLUMBING"
CDS_LIB"mstr_standard";
"B \NAC \NWC"2;
"S \NAC"
BN"1"148;
%"TAP"
"6","(-1975,3100)","2","mstr_standard","I146";
;
HDL_TAP"TRUE"
BODY_TYPE"PLUMBING"
CDS_LIB"mstr_standard";
"B \NAC \NWC"1;
"S \NAC"
BN"2"151;
%"TAP"
"6","(-1975,3200)","2","mstr_standard","I147";
;
HDL_TAP"TRUE"
BODY_TYPE"PLUMBING"
CDS_LIB"mstr_standard";
"B \NAC \NWC"1;
"S \NAC"
BN"3"153;
%"TAP"
"6","(-1975,3500)","2","mstr_standard","I148";
;
HDL_TAP"TRUE"
BODY_TYPE"PLUMBING"
CDS_LIB"mstr_standard";
"B \NAC \NWC"1;
"S \NAC"
BN"6"159;
%"TAP"
"6","(-1975,3400)","2","mstr_standard","I149";
;
HDL_TAP"TRUE"
BODY_TYPE"PLUMBING"
CDS_LIB"mstr_standard";
"B \NAC \NWC"1;
"S \NAC"
BN"5"157;
%"TAP"
"6","(-1975,3300)","2","mstr_standard","I150";
;
HDL_TAP"TRUE"
BODY_TYPE"PLUMBING"
CDS_LIB"mstr_standard";
"B \NAC \NWC"1;
"S \NAC"
BN"4"155;
%"TAP"
"6","(-1775,3150)","2","mstr_standard","I151";
;
HDL_TAP"TRUE"
BODY_TYPE"PLUMBING"
CDS_LIB"mstr_standard";
"B \NAC \NWC"2;
"S \NAC"
BN"3"152;
%"TAP"
"6","(-1775,3050)","2","mstr_standard","I152";
;
HDL_TAP"TRUE"
BODY_TYPE"PLUMBING"
CDS_LIB"mstr_standard";
"B \NAC \NWC"2;
"S \NAC"
BN"2"150;
%"TAP"
"6","(-1775,3250)","2","mstr_standard","I153";
;
HDL_TAP"TRUE"
BODY_TYPE"PLUMBING"
CDS_LIB"mstr_standard";
"B \NAC \NWC"2;
"S \NAC"
BN"4"154;
%"TAP"
"6","(-1775,3350)","2","mstr_standard","I154";
;
HDL_TAP"TRUE"
BODY_TYPE"PLUMBING"
CDS_LIB"mstr_standard";
"B \NAC \NWC"2;
"S \NAC"
BN"5"156;
%"TAP"
"6","(-1775,3450)","2","mstr_standard","I155";
;
HDL_TAP"TRUE"
BODY_TYPE"PLUMBING"
CDS_LIB"mstr_standard";
"B \NAC \NWC"2;
"S \NAC"
BN"6"158;
%"GND"
"1","(-175,550)","2","mstr_symbols","I156";
;
HDL_POWER"GND"
ROOM"DDR4_GH_G"
BODY_TYPE"PLUMBING"
BOM_COST"MEM"
SIZE"1B"
CDS_LIB"mstr_symbols"
VOLTAGE"0";
"A\NAC"15;
%"TAP"
"6","(-1975,3800)","2","mstr_standard","I157";
;
HDL_TAP"TRUE"
BODY_TYPE"PLUMBING"
CDS_LIB"mstr_standard";
"B \NAC \NWC"1;
"S \NAC"
BN"9"165;
%"TAP"
"6","(-1975,3600)","2","mstr_standard","I158";
;
HDL_TAP"TRUE"
BODY_TYPE"PLUMBING"
CDS_LIB"mstr_standard";
"B \NAC \NWC"1;
"S \NAC"
BN"7"161;
%"TAP"
"6","(-1975,3700)","2","mstr_standard","I159";
;
HDL_TAP"TRUE"
BODY_TYPE"PLUMBING"
CDS_LIB"mstr_standard";
"B \NAC \NWC"1;
"S \NAC"
BN"8"163;
%"TAP"
"6","(-1975,4000)","2","mstr_standard","I160";
;
HDL_TAP"TRUE"
BODY_TYPE"PLUMBING"
CDS_LIB"mstr_standard";
"B \NAC \NWC"1;
"S \NAC"
BN"11"146;
%"TAP"
"6","(-1975,3900)","2","mstr_standard","I161";
;
HDL_TAP"TRUE"
BODY_TYPE"PLUMBING"
CDS_LIB"mstr_standard";
"B \NAC \NWC"1;
"S \NAC"
BN"10"144;
%"TAP"
"6","(-1775,3650)","2","mstr_standard","I162";
;
HDL_TAP"TRUE"
BODY_TYPE"PLUMBING"
CDS_LIB"mstr_standard";
"B \NAC \NWC"2;
"S \NAC"
BN"8"162;
%"TAP"
"6","(-1775,3550)","2","mstr_standard","I163";
;
HDL_TAP"TRUE"
BODY_TYPE"PLUMBING"
CDS_LIB"mstr_standard";
"B \NAC \NWC"2;
"S \NAC"
BN"7"160;
%"TAP"
"6","(-1775,3750)","2","mstr_standard","I164";
;
HDL_TAP"TRUE"
BODY_TYPE"PLUMBING"
CDS_LIB"mstr_standard";
"B \NAC \NWC"2;
"S \NAC"
BN"9"164;
%"TAP"
"6","(-1775,3850)","2","mstr_standard","I165";
;
HDL_TAP"TRUE"
BODY_TYPE"PLUMBING"
CDS_LIB"mstr_standard";
"B \NAC \NWC"2;
"S \NAC"
BN"10"143;
%"TAP"
"6","(-1775,3950)","2","mstr_standard","I166";
;
HDL_TAP"TRUE"
BODY_TYPE"PLUMBING"
CDS_LIB"mstr_standard";
"B \NAC \NWC"2;
"S \NAC"
BN"11"145;
%"TAP"
"6","(-1775,4050)","2","mstr_standard","I167";
;
HDL_TAP"TRUE"
BODY_TYPE"PLUMBING"
CDS_LIB"mstr_standard";
"B \NAC \NWC"2;
"S \NAC"
BN"12"147;
%"TAP"
"6","(-1975,4300)","2","mstr_standard","I168";
;
HDL_TAP"TRUE"
BODY_TYPE"PLUMBING"
CDS_LIB"mstr_standard";
"B \NAC \NWC"1;
"S \NAC"
BN"14"170;
%"TAP"
"6","(-1975,4200)","2","mstr_standard","I169";
;
HDL_TAP"TRUE"
BODY_TYPE"PLUMBING"
CDS_LIB"mstr_standard";
"B \NAC \NWC"1;
"S \NAC"
BN"13"168;
%"TAP"
"6","(-1975,4100)","2","mstr_standard","I170";
;
HDL_TAP"TRUE"
BODY_TYPE"PLUMBING"
CDS_LIB"mstr_standard";
"B \NAC \NWC"1;
"S \NAC"
BN"12"166;
%"TAP"
"6","(-1975,4400)","2","mstr_standard","I171";
;
HDL_TAP"TRUE"
BODY_TYPE"PLUMBING"
CDS_LIB"mstr_standard";
"B \NAC \NWC"1;
"S \NAC"
BN"15"172;
%"TAP"
"6","(-1975,4500)","2","mstr_standard","I172";
;
HDL_TAP"TRUE"
BODY_TYPE"PLUMBING"
CDS_LIB"mstr_standard";
"B \NAC \NWC"1;
"S \NAC"
BN"16"174;
%"TAP"
"6","(-1775,4150)","2","mstr_standard","I173";
;
HDL_TAP"TRUE"
BODY_TYPE"PLUMBING"
CDS_LIB"mstr_standard";
"B \NAC \NWC"2;
"S \NAC"
BN"13"167;
%"TAP"
"6","(-1775,4250)","2","mstr_standard","I174";
;
HDL_TAP"TRUE"
BODY_TYPE"PLUMBING"
CDS_LIB"mstr_standard";
"B \NAC \NWC"2;
"S \NAC"
BN"14"169;
%"TAP"
"6","(-1775,4350)","2","mstr_standard","I175";
;
HDL_TAP"TRUE"
BODY_TYPE"PLUMBING"
CDS_LIB"mstr_standard";
"B \NAC \NWC"2;
"S \NAC"
BN"15"171;
%"TAP"
"6","(-1775,4450)","2","mstr_standard","I176";
;
HDL_TAP"TRUE"
BODY_TYPE"PLUMBING"
CDS_LIB"mstr_standard";
"B \NAC \NWC"2;
"S \NAC"
BN"16"173;
%"TAP"
"6","(-1775,4550)","2","mstr_standard","I177";
;
HDL_TAP"TRUE"
BODY_TYPE"PLUMBING"
CDS_LIB"mstr_standard";
"B \NAC \NWC"2;
"S \NAC"
BN"17"175;
%"TAP"
"6","(-1975,4600)","2","mstr_standard","I178";
;
HDL_TAP"TRUE"
BODY_TYPE"PLUMBING"
CDS_LIB"mstr_standard";
"B \NAC \NWC"1;
"S \NAC"
BN"17"176;
%"P12V_NVDIMM_GHJ"
"1","(-2375,2425)","0","mstr_symbols","I181";
;
HDL_POWER"P12V_NVDIMM_GHJ"
BODY_TYPE"PLUMBING"
CDS_LIB"mstr_symbols"
VOLTAGE"12.0";
"G\NAC"16;
%"SCONN288_H44441003"
"1","(-5225,2700)","0","mstr_sconn","I24";
;
CDS_SEC"1"
ROOM"DDR4_GH_H"
CDS_LOCATION"J9U1"
SEC"1"
SEC_TYPE"PIP"
CDS_LIB"mstr_sconn"
BOM_COST"MEM"
PACK_TYPE"PIP"
MATERIAL"SCONN"
PART_NUMBER"H44441-003"
LOCATION"J9U1";
"DQ<63>"
$PN"280"140;
"BA<1>"
$PN"224"70;
"CK1N"
$PN"219"77;
"CK0P"
$PN"74"63;
"S3_N_C<1>"
$PN"237"64;
"S2_N_C<0>"
$PN"93"65;
"S1_N"
$PN"89"66;
"DQ<29>"
$PN"181"88;
"DQ<28>"
$PN"36"89;
"C<2>"
$PN"235"62;
"A0"
$PN"79"71;
"A1"
$PN"72"72;
"A12"
$PN"65"129;
"A13"
$PN"232"130;
"A17"
$PN"234"131;
"A3"
$PN"71"78;
"A4"
$PN"214"79;
"A5"
$PN"213"80;
"A6"
$PN"69"81;
"A7"
$PN"211"82;
"A8"
$PN"68"83;
"A9"
$PN"66"84;
"CB<6>"
$PN"54"53;
"CB<5>"
$PN"192"54;
"CB<4>"
$PN"47"55;
"CB<3>"
$PN"201"56;
"CB<2>"
$PN"56"57;
"CB<1>"
$PN"194"32;
"CB<0>"
$PN"49"33;
"CK0N"
$PN"75"69;
"CKE<1>"
$PN"203"67;
"DQ<62>"
$PN"135"139;
"DQ<61>"
$PN"273"135;
"DQ<60>"
$PN"128"136;
"DQ<59>"
$PN"282"137;
"DQ<56>"
$PN"130"109;
"DQ<55>"
$PN"269"110;
"DQ<46>"
$PN"113"111;
"DQ<45>"
$PN"251"112;
"DQ<44>"
$PN"106"113;
"DQ<43>"
$PN"260"114;
"DQ<42>"
$PN"115"115;
"DQ<41>"
$PN"253"116;
"DQ<40>"
$PN"108"117;
"DQ<39>"
$PN"247"118;
"DQ<37>"
$PN"240"90;
"DQ<34>"
$PN"104"91;
"DQ<33>"
$PN"242"92;
"DQ<32>"
$PN"97"93;
"DQ<31>"
$PN"188"94;
"DQ<30>"
$PN"43"95;
"DQ<25>"
$PN"183"106;
"DQ<24>"
$PN"38"96;
"DQ<23>"
$PN"177"105;
"DQ<22>"
$PN"32"97;
"DQ<21>"
$PN"170"98;
"DQ<20>"
$PN"25"99;
"DQ<19>"
$PN"179"108;
"DQ<18>"
$PN"34"100;
"DQ<16>"
$PN"27"34;
"DQ<14>"
$PN"21"48;
"DQ<13>"
$PN"159"35;
"DQ<12>"
$PN"14"50;
"DQ<11>"
$PN"168"36;
"DQ<10>"
$PN"23"37;
"DQ<9>"
$PN"161"47;
"DQ<8>"
$PN"16"38;
"DQ<7>"
$PN"155"46;
"DQ<6>"
$PN"10"39;
"EVENT_N"
$PN"78"22;
"PAR"
$PN"222"51;
"RESET_N"
$PN"58"52;
"RFU<2>"
$PN"144"24;
"SCL"
$PN"141"29;
"SDA"
$PN"285"30;
"VREFCA"
$PN"146"23;
"CK1P"
$PN"218"76;
"BG<0>"
$PN"63"73;
"BG<1>"
$PN"207"74;
"BA<0>"
$PN"81"75;
"SA<0>"
$PN"139"20;
"VDDSPD"
$PN"284"20;
"SA<2>"
$PN"238"13;
"SA<1>"
$PN"140"20;
"DQ<1>"
$PN"150"40;
"DQ<0>"
$PN"5"41;
"ACT_N"
$PN"62"27;
"ALERT_N"
$PN"208"31;
"A2"
$PN"216"85;
"DQ<35>"
$PN"249"101;
"DQ<36>"
$PN"95"102;
"DQ<38>"
$PN"102"119;
"A10"
$PN"225"86;
"A11"
$PN"210"87;
"A14_WE_N"
$PN"228"132;
"A15_CAS_N"
$PN"86"133;
"A16_RAS_N"
$PN"82"134;
"CB<7>"
$PN"199"58;
"ODT<0>"
$PN"87"59;
"ODT<1>"
$PN"91"60;
"CKE<0>"
$PN"60"61;
"S0_N"
$PN"84"68;
"DQ<27>"
$PN"190"103;
"DQ<26>"
$PN"45"107;
"DQ<15>"
$PN"166"42;
"DQ<17>"
$PN"172"104;
"RFU<0>"
$PN"205"25;
"RFU<1>"
$PN"227"26;
"SAVE_N_NC"
$PN"230"28;
"DQ<57>"
$PN"275"120;
"DQ<58>"
$PN"137"138;
"DQ<54>"
$PN"124"121;
"DQ<53>"
$PN"262"122;
"DQ<52>"
$PN"117"123;
"DQ<51>"
$PN"271"124;
"DQ<50>"
$PN"126"128;
"DQ<49>"
$PN"264"125;
"DQ<48>"
$PN"119"126;
"DQ<47>"
$PN"258"127;
"DQ<2>"
$PN"12"44;
"DQ<3>"
$PN"157"45;
"DQ<4>"
$PN"3"43;
"DQ<5>"
$PN"148"49;
%"TAP"
"6","(-5975,1950)","0","mstr_standard","I25";
;
HDL_TAP"TRUE"
BODY_TYPE"PLUMBING"
CDS_LIB"mstr_standard";
"B \NAC \NWC"12;
"S \NAC"
BN"0"33;
%"TAP"
"6","(-5975,2000)","0","mstr_standard","I26";
;
HDL_TAP"TRUE"
BODY_TYPE"PLUMBING"
CDS_LIB"mstr_standard";
"B \NAC \NWC"12;
"S \NAC"
BN"1"32;
%"TAP"
"6","(-5975,2100)","0","mstr_standard","I27";
;
HDL_TAP"TRUE"
BODY_TYPE"PLUMBING"
CDS_LIB"mstr_standard";
"B \NAC \NWC"12;
"S \NAC"
BN"3"56;
%"TAP"
"6","(-5975,2050)","0","mstr_standard","I28";
;
HDL_TAP"TRUE"
BODY_TYPE"PLUMBING"
CDS_LIB"mstr_standard";
"B \NAC \NWC"12;
"S \NAC"
BN"2"57;
%"TAP"
"6","(-5975,2200)","0","mstr_standard","I29";
;
HDL_TAP"TRUE"
BODY_TYPE"PLUMBING"
CDS_LIB"mstr_standard";
"B \NAC \NWC"12;
"S \NAC"
BN"5"54;
%"CAP_A"
"1","(-7225,1000)","2","dev_discrete","I3";
;
ROOM"DDR4_GH_G"
$SEC"1"
CDS_SEC"1"
CDS_LIB"dev_discrete"
BOM_COST"MEM"
CDS_LOCATION"C1G10"
MATERIAL"X7R"
VOLTAGE"25V"
PACK_TYPE"0402V"
TOLERANCE"10%"
VALUE"0.01UF"
PART_NUMBER"A36096-045"
LOCATION"C1G10";
"B"
$PN"2"17;
"A"
$PN"1"23;
%"TAP"
"6","(-5975,2150)","0","mstr_standard","I30";
;
HDL_TAP"TRUE"
BODY_TYPE"PLUMBING"
CDS_LIB"mstr_standard";
"B \NAC \NWC"12;
"S \NAC"
BN"4"55;
%"TAP"
"6","(-5975,2250)","0","mstr_standard","I31";
;
HDL_TAP"TRUE"
BODY_TYPE"PLUMBING"
CDS_LIB"mstr_standard";
"B \NAC \NWC"12;
"S \NAC"
BN"6"53;
%"TAP"
"6","(-5975,2300)","0","mstr_standard","I32";
;
HDL_TAP"TRUE"
BODY_TYPE"PLUMBING"
CDS_LIB"mstr_standard";
"B \NAC \NWC"12;
"S \NAC"
BN"7"58;
%"TAP"
"6","(-5975,2400)","0","mstr_standard","I33";
;
HDL_TAP"TRUE"
BODY_TYPE"PLUMBING"
CDS_LIB"mstr_standard";
"B \NAC \NWC"11;
"S \NAC"
BN"2"59;
%"TAP"
"6","(-5975,2450)","0","mstr_standard","I34";
;
HDL_TAP"TRUE"
BODY_TYPE"PLUMBING"
CDS_LIB"mstr_standard";
"B \NAC \NWC"11;
"S \NAC"
BN"3"60;
%"TAP"
"6","(-6175,3000)","0","mstr_standard","I35";
;
HDL_TAP"TRUE"
BODY_TYPE"PLUMBING"
CDS_LIB"mstr_standard";
"B \NAC \NWC"7;
"S \NAC"
BN"2"69;
%"TAP"
"6","(-6175,3100)","0","mstr_standard","I36";
;
HDL_TAP"TRUE"
BODY_TYPE"PLUMBING"
CDS_LIB"mstr_standard";
"B \NAC \NWC"7;
"S \NAC"
BN"3"77;
%"TAP"
"6","(-5975,2600)","0","mstr_standard","I37";
;
HDL_TAP"TRUE"
BODY_TYPE"PLUMBING"
CDS_LIB"mstr_standard";
"B \NAC \NWC"9;
"S \NAC"
BN"3"67;
%"TAP"
"6","(-5975,2550)","0","mstr_standard","I38";
;
HDL_TAP"TRUE"
BODY_TYPE"PLUMBING"
CDS_LIB"mstr_standard";
"B \NAC \NWC"9;
"S \NAC"
BN"2"61;
%"TAP"
"6","(-5975,2750)","0","mstr_standard","I39";
;
HDL_TAP"TRUE"
BODY_TYPE"PLUMBING"
CDS_LIB"mstr_standard";
"B \NAC \NWC"8;
"S \NAC"
BN"5"66;
%"GND"
"1","(-7225,750)","0","mstr_symbols","I4";
;
HDL_POWER"GND"
ROOM"DDR4_GH_G"
BODY_TYPE"PLUMBING"
CDS_LIB"mstr_symbols"
SIZE"1B"
BOM_COST"MEM"
VOLTAGE"0";
"A\NAC"17;
%"TAP"
"6","(-5975,2700)","0","mstr_standard","I40";
;
HDL_TAP"TRUE"
BODY_TYPE"PLUMBING"
CDS_LIB"mstr_standard";
"B \NAC \NWC"8;
"S \NAC"
BN"4"68;
%"TAP"
"6","(-5975,2850)","0","mstr_standard","I41";
;
HDL_TAP"TRUE"
BODY_TYPE"PLUMBING"
CDS_LIB"mstr_standard";
"B \NAC \NWC"8;
"S \NAC"
BN"7"64;
%"TAP"
"6","(-5975,2800)","0","mstr_standard","I42";
;
HDL_TAP"TRUE"
BODY_TYPE"PLUMBING"
CDS_LIB"mstr_standard";
"B \NAC \NWC"8;
"S \NAC"
BN"6"65;
%"TAP"
"6","(-5975,3150)","0","mstr_standard","I43";
;
HDL_TAP"TRUE"
BODY_TYPE"PLUMBING"
CDS_LIB"mstr_standard";
"B \NAC \NWC"10;
"S \NAC"
BN"3"76;
%"TAP"
"6","(-5975,3050)","0","mstr_standard","I44";
;
HDL_TAP"TRUE"
BODY_TYPE"PLUMBING"
CDS_LIB"mstr_standard";
"B \NAC \NWC"10;
"S \NAC"
BN"2"63;
%"TAP"
"6","(-5975,3250)","0","mstr_standard","I45";
;
HDL_TAP"TRUE"
BODY_TYPE"PLUMBING"
CDS_LIB"mstr_standard";
"B \NAC \NWC"6;
"S \NAC"
BN"0"73;
%"TAP"
"6","(-5975,3350)","0","mstr_standard","I46";
;
HDL_TAP"TRUE"
BODY_TYPE"PLUMBING"
CDS_LIB"mstr_standard";
"B \NAC \NWC"5;
"S \NAC"
BN"0"75;
%"TAP"
"6","(-5975,3300)","0","mstr_standard","I47";
;
HDL_TAP"TRUE"
BODY_TYPE"PLUMBING"
CDS_LIB"mstr_standard";
"B \NAC \NWC"6;
"S \NAC"
BN"1"74;
%"TAP"
"6","(-5975,3400)","0","mstr_standard","I48";
;
HDL_TAP"TRUE"
BODY_TYPE"PLUMBING"
CDS_LIB"mstr_standard";
"B \NAC \NWC"5;
"S \NAC"
BN"1"70;
%"TAP"
"6","(-5975,3500)","0","mstr_standard","I49";
;
HDL_TAP"TRUE"
BODY_TYPE"PLUMBING"
CDS_LIB"mstr_standard";
"B \NAC \NWC"4;
"S \NAC"
BN"0"71;
%"TAP"
"6","(-4475,1200)","2","mstr_standard","I50";
;
HDL_TAP"TRUE"
BODY_TYPE"PLUMBING"
CDS_LIB"mstr_standard";
"B \NAC \NWC"3;
"S \NAC"
BN"0"41;
%"TAP"
"6","(-4475,1350)","2","mstr_standard","I51";
;
HDL_TAP"TRUE"
BODY_TYPE"PLUMBING"
CDS_LIB"mstr_standard";
"B \NAC \NWC"3;
"S \NAC"
BN"3"45;
%"TAP"
"6","(-4475,1250)","2","mstr_standard","I52";
;
HDL_TAP"TRUE"
BODY_TYPE"PLUMBING"
CDS_LIB"mstr_standard";
"B \NAC \NWC"3;
"S \NAC"
BN"1"40;
%"TAP"
"6","(-4475,1300)","2","mstr_standard","I53";
;
HDL_TAP"TRUE"
BODY_TYPE"PLUMBING"
CDS_LIB"mstr_standard";
"B \NAC \NWC"3;
"S \NAC"
BN"2"44;
%"TAP"
"6","(-4475,1450)","2","mstr_standard","I54";
;
HDL_TAP"TRUE"
BODY_TYPE"PLUMBING"
CDS_LIB"mstr_standard";
"B \NAC \NWC"3;
"S \NAC"
BN"5"49;
%"TAP"
"6","(-4475,1400)","2","mstr_standard","I55";
;
HDL_TAP"TRUE"
BODY_TYPE"PLUMBING"
CDS_LIB"mstr_standard";
"B \NAC \NWC"3;
"S \NAC"
BN"4"43;
%"SCONN288_H44441003"
"4","(-3075,1450)","0","mstr_sconn","I56";
;
CDS_SEC"4"
ROOM"DDR4_GH_H"
CDS_LOCATION"J9U1"
SEC"4"
SEC_TYPE"PIP"
CDS_LIB"mstr_sconn"
BOM_COST"MEM"
PACK_TYPE"PIP"
MATERIAL"SCONN"
PART_NUMBER"H44441-003"
LOCATION"J9U1";
"VDD<0>"
$PN"236"18;
"VDD<6>"
$PN"220"18;
"VDD<10>"
$PN"209"18;
"VDD<13>"
$PN"92"18;
"VDD<16>"
$PN"85"18;
"VDD<19>"
$PN"76"18;
"VDD<23>"
$PN"64"18;
"VDD<25>"
$PN"59"18;
"VTT<0>"
$PN"221"19;
"12V<1>"
$PN"1"16;
"12V<0>"
$PN"145"16;
"VDD<24>"
$PN"61"18;
"VDD<22>"
$PN"67"18;
"VDD<21>"
$PN"70"18;
"VDD<20>"
$PN"73"18;
"VDD<18>"
$PN"80"18;
"VDD<17>"
$PN"83"18;
"VDD<15>"
$PN"88"18;
"VDD<14>"
$PN"90"18;
"VDD<12>"
$PN"204"18;
"VDD<11>"
$PN"206"18;
"VDD<9>"
$PN"212"18;
"VDD<8>"
$PN"215"18;
"VDD<7>"
$PN"217"18;
"VDD<5>"
$PN"223"18;
"VDD<4>"
$PN"226"18;
"VDD<3>"
$PN"229"18;
"VDD<2>"
$PN"231"18;
"VDD<1>"
$PN"233"18;
"VPP<4>"
$PN"142"21;
"VPP<3>"
$PN"143"21;
"VPP<2>"
$PN"288"21;
"VPP<1>"
$PN"286"21;
"VPP<0>"
$PN"287"21;
"VTT<1>"
$PN"77"19;
%"TAP"
"6","(-4475,1550)","2","mstr_standard","I57";
;
HDL_TAP"TRUE"
BODY_TYPE"PLUMBING"
CDS_LIB"mstr_standard";
"B \NAC \NWC"3;
"S \NAC"
BN"7"46;
%"TAP"
"6","(-4475,1500)","2","mstr_standard","I58";
;
HDL_TAP"TRUE"
BODY_TYPE"PLUMBING"
CDS_LIB"mstr_standard";
"B \NAC \NWC"3;
"S \NAC"
BN"6"39;
%"TAP"
"6","(-4475,1600)","2","mstr_standard","I59";
;
HDL_TAP"TRUE"
BODY_TYPE"PLUMBING"
CDS_LIB"mstr_standard";
"B \NAC \NWC"3;
"S \NAC"
BN"8"38;
%"TAP"
"6","(-4475,1650)","2","mstr_standard","I60";
;
HDL_TAP"TRUE"
BODY_TYPE"PLUMBING"
CDS_LIB"mstr_standard";
"B \NAC \NWC"3;
"S \NAC"
BN"9"47;
%"TAP"
"6","(-4475,1700)","2","mstr_standard","I61";
;
HDL_TAP"TRUE"
BODY_TYPE"PLUMBING"
CDS_LIB"mstr_standard";
"B \NAC \NWC"3;
"S \NAC"
BN"10"37;
%"TAP"
"6","(-4475,1750)","2","mstr_standard","I62";
;
HDL_TAP"TRUE"
BODY_TYPE"PLUMBING"
CDS_LIB"mstr_standard";
"B \NAC \NWC"3;
"S \NAC"
BN"11"36;
%"TAP"
"6","(-4475,1850)","2","mstr_standard","I63";
;
HDL_TAP"TRUE"
BODY_TYPE"PLUMBING"
CDS_LIB"mstr_standard";
"B \NAC \NWC"3;
"S \NAC"
BN"13"35;
%"TAP"
"6","(-4475,1800)","2","mstr_standard","I64";
;
HDL_TAP"TRUE"
BODY_TYPE"PLUMBING"
CDS_LIB"mstr_standard";
"B \NAC \NWC"3;
"S \NAC"
BN"12"50;
%"TAP"
"6","(-4475,2000)","2","mstr_standard","I65";
;
HDL_TAP"TRUE"
BODY_TYPE"PLUMBING"
CDS_LIB"mstr_standard";
"B \NAC \NWC"3;
"S \NAC"
BN"16"34;
%"TAP"
"6","(-4475,1900)","2","mstr_standard","I66";
;
HDL_TAP"TRUE"
BODY_TYPE"PLUMBING"
CDS_LIB"mstr_standard";
"B \NAC \NWC"3;
"S \NAC"
BN"14"48;
%"TAP"
"6","(-4475,1950)","2","mstr_standard","I67";
;
HDL_TAP"TRUE"
BODY_TYPE"PLUMBING"
CDS_LIB"mstr_standard";
"B \NAC \NWC"3;
"S \NAC"
BN"15"42;
%"TAP"
"6","(-4475,2050)","2","mstr_standard","I68";
;
HDL_TAP"TRUE"
BODY_TYPE"PLUMBING"
CDS_LIB"mstr_standard";
"B \NAC \NWC"3;
"S \NAC"
BN"17"104;
%"TAP"
"6","(-4475,2100)","2","mstr_standard","I69";
;
HDL_TAP"TRUE"
BODY_TYPE"PLUMBING"
CDS_LIB"mstr_standard";
"B \NAC \NWC"3;
"S \NAC"
BN"18"100;
%"TAP"
"6","(-4475,2250)","2","mstr_standard","I70";
;
HDL_TAP"TRUE"
BODY_TYPE"PLUMBING"
CDS_LIB"mstr_standard";
"B \NAC \NWC"3;
"S \NAC"
BN"21"98;
%"TAP"
"6","(-4475,2150)","2","mstr_standard","I71";
;
HDL_TAP"TRUE"
BODY_TYPE"PLUMBING"
CDS_LIB"mstr_standard";
"B \NAC \NWC"3;
"S \NAC"
BN"19"108;
%"TAP"
"6","(-4475,2200)","2","mstr_standard","I72";
;
HDL_TAP"TRUE"
BODY_TYPE"PLUMBING"
CDS_LIB"mstr_standard";
"B \NAC \NWC"3;
"S \NAC"
BN"20"99;
%"TAP"
"6","(-4475,2300)","2","mstr_standard","I73";
;
HDL_TAP"TRUE"
BODY_TYPE"PLUMBING"
CDS_LIB"mstr_standard";
"B \NAC \NWC"3;
"S \NAC"
BN"22"97;
%"TAP"
"6","(-4475,2350)","2","mstr_standard","I74";
;
HDL_TAP"TRUE"
BODY_TYPE"PLUMBING"
CDS_LIB"mstr_standard";
"B \NAC \NWC"3;
"S \NAC"
BN"23"105;
%"TAP"
"6","(-4475,2500)","2","mstr_standard","I75";
;
HDL_TAP"TRUE"
BODY_TYPE"PLUMBING"
CDS_LIB"mstr_standard";
"B \NAC \NWC"3;
"S \NAC"
BN"26"107;
%"TAP"
"6","(-4475,2450)","2","mstr_standard","I76";
;
HDL_TAP"TRUE"
BODY_TYPE"PLUMBING"
CDS_LIB"mstr_standard";
"B \NAC \NWC"3;
"S \NAC"
BN"25"106;
%"TAP"
"6","(-4475,2400)","2","mstr_standard","I77";
;
HDL_TAP"TRUE"
BODY_TYPE"PLUMBING"
CDS_LIB"mstr_standard";
"B \NAC \NWC"3;
"S \NAC"
BN"24"96;
%"PVDDQ_GHJ"
"1","(-4175,1975)","0","mstr_symbols","I78";
;
HDL_POWER"PVDDQ_GHJ"
ROOM"DDR4_GH_G"
BODY_TYPE"PLUMBING"
CDS_LIB"mstr_symbols"
BOM_COST"MEM"
VOLTAGE"1.2V";
"G\NAC"18;
%"PVTT_GHJ"
"1","(-3925,2150)","0","mstr_symbols","I79";
;
HDL_POWER"PVTT_GHJ"
ROOM"DDR4_GH_G"
BODY_TYPE"PLUMBING"
CDS_LIB"mstr_symbols"
BOM_COST"MEM"
VOLTAGE"0.6V";
"G\NAC"19;
%"PVPP_GHJ"
"1","(-7825,1700)","0","mstr_symbols","I8";
;
HDL_POWER"PVPP_GHJ"
ROOM"DDR4_GH_G"
BODY_TYPE"PLUMBING"
CDS_LIB"mstr_symbols"
BOM_COST"MEM"
VOLTAGE"2.5V";
"G\NAC"20;
%"PVPP_GHJ"
"1","(-3775,2450)","0","mstr_symbols","I80";
;
HDL_POWER"PVPP_GHJ"
ROOM"DDR4_GH_G"
BODY_TYPE"PLUMBING"
CDS_LIB"mstr_symbols"
BOM_COST"MEM"
VOLTAGE"2.5V";
"G\NAC"21;
%"TAP"
"6","(-4475,2550)","2","mstr_standard","I81";
;
HDL_TAP"TRUE"
BODY_TYPE"PLUMBING"
CDS_LIB"mstr_standard";
"B \NAC \NWC"3;
"S \NAC"
BN"27"103;
%"TAP"
"6","(-4475,2600)","2","mstr_standard","I82";
;
HDL_TAP"TRUE"
BODY_TYPE"PLUMBING"
CDS_LIB"mstr_standard";
"B \NAC \NWC"3;
"S \NAC"
BN"28"89;
%"TAP"
"6","(-4475,2650)","2","mstr_standard","I83";
;
HDL_TAP"TRUE"
BODY_TYPE"PLUMBING"
CDS_LIB"mstr_standard";
"B \NAC \NWC"3;
"S \NAC"
BN"29"88;
%"TAP"
"6","(-4475,2750)","2","mstr_standard","I84";
;
HDL_TAP"TRUE"
BODY_TYPE"PLUMBING"
CDS_LIB"mstr_standard";
"B \NAC \NWC"3;
"S \NAC"
BN"31"94;
%"TAP"
"6","(-4475,2700)","2","mstr_standard","I85";
;
HDL_TAP"TRUE"
BODY_TYPE"PLUMBING"
CDS_LIB"mstr_standard";
"B \NAC \NWC"3;
"S \NAC"
BN"30"95;
%"TAP"
"6","(-4475,2850)","2","mstr_standard","I86";
;
HDL_TAP"TRUE"
BODY_TYPE"PLUMBING"
CDS_LIB"mstr_standard";
"B \NAC \NWC"3;
"S \NAC"
BN"33"92;
%"TAP"
"6","(-4475,2800)","2","mstr_standard","I87";
;
HDL_TAP"TRUE"
BODY_TYPE"PLUMBING"
CDS_LIB"mstr_standard";
"B \NAC \NWC"3;
"S \NAC"
BN"32"93;
%"TAP"
"6","(-4475,2900)","2","mstr_standard","I88";
;
HDL_TAP"TRUE"
BODY_TYPE"PLUMBING"
CDS_LIB"mstr_standard";
"B \NAC \NWC"3;
"S \NAC"
BN"34"91;
%"TAP"
"6","(-4475,3000)","2","mstr_standard","I89";
;
HDL_TAP"TRUE"
BODY_TYPE"PLUMBING"
CDS_LIB"mstr_standard";
"B \NAC \NWC"3;
"S \NAC"
BN"36"102;
%"TAP"
"6","(-4475,2950)","2","mstr_standard","I90";
;
HDL_TAP"TRUE"
BODY_TYPE"PLUMBING"
CDS_LIB"mstr_standard";
"B \NAC \NWC"3;
"S \NAC"
BN"35"101;
%"TAP"
"6","(-4475,3100)","2","mstr_standard","I91";
;
HDL_TAP"TRUE"
BODY_TYPE"PLUMBING"
CDS_LIB"mstr_standard";
"B \NAC \NWC"3;
"S \NAC"
BN"38"119;
%"TAP"
"6","(-4475,3050)","2","mstr_standard","I92";
;
HDL_TAP"TRUE"
BODY_TYPE"PLUMBING"
CDS_LIB"mstr_standard";
"B \NAC \NWC"3;
"S \NAC"
BN"37"90;
%"TAP"
"6","(-4475,3150)","2","mstr_standard","I93";
;
HDL_TAP"TRUE"
BODY_TYPE"PLUMBING"
CDS_LIB"mstr_standard";
"B \NAC \NWC"3;
"S \NAC"
BN"39"118;
%"TAP"
"6","(-4475,3250)","2","mstr_standard","I94";
;
HDL_TAP"TRUE"
BODY_TYPE"PLUMBING"
CDS_LIB"mstr_standard";
"B \NAC \NWC"3;
"S \NAC"
BN"41"116;
%"TAP"
"6","(-4475,3200)","2","mstr_standard","I95";
;
HDL_TAP"TRUE"
BODY_TYPE"PLUMBING"
CDS_LIB"mstr_standard";
"B \NAC \NWC"3;
"S \NAC"
BN"40"117;
%"TAP"
"6","(-4475,3350)","2","mstr_standard","I96";
;
HDL_TAP"TRUE"
BODY_TYPE"PLUMBING"
CDS_LIB"mstr_standard";
"B \NAC \NWC"3;
"S \NAC"
BN"43"114;
%"TAP"
"6","(-4475,3300)","2","mstr_standard","I97";
;
HDL_TAP"TRUE"
BODY_TYPE"PLUMBING"
CDS_LIB"mstr_standard";
"B \NAC \NWC"3;
"S \NAC"
BN"42"115;
%"TAP"
"6","(-4475,3400)","2","mstr_standard","I98";
;
HDL_TAP"TRUE"
BODY_TYPE"PLUMBING"
CDS_LIB"mstr_standard";
"B \NAC \NWC"3;
"S \NAC"
BN"44"113;
%"TAP"
"6","(-4475,3500)","2","mstr_standard","I99";
;
HDL_TAP"TRUE"
BODY_TYPE"PLUMBING"
CDS_LIB"mstr_standard";
"B \NAC \NWC"3;
"S \NAC"
BN"46"111;
END.
